# BASEBOARD_FAB2 (Tioga Pass) — schematic netlist excerpt (pin names and nets, part order shuffled) for the footprints in the layout excerpt that follows; sources: Cadence DE-HDL packaged netlist, KiCad conversion of Wiwynn_Tioga_Pass_MB.brd

C25W48  CAP  1.0UF 16V 10% X6S  pkg 0402  page 149 : A = P3V3_STBY ; B = GND
R2T5  RES  1.00K 1% CHIP  pkg 0402  page 157 : A = P3V3_STBY ; B = H_CPU0_FAST_WAKE

U9F1  FSA3357  IC  pkg SM  page 158
  B0  = SP2_BMC_CM_UART_RX_R
  B1  = UART_BMC_RXD5
  B2  = SP1_BMC_HOST_UART_RX
  GND  = GND
  S2  = FM_UARTSW_MSB_N
  S1  = FM_UARTSW_LSB_N
  A  = UART_MUX_IN_R
  VCC  = P3V3_STBY

(kicad_pcb
	(version 20260206)
	(generator "pcbnew")
	(generator_version "10.0")
	(general
		(thickness 1.6)
		(legacy_teardrops no)
	)
	(paper "A4")
	(title_block
		(title "Wiwynn_Tioga_Pass_MB.brd")
		(comment 1 "Tioga Pass / footprints 3394-3396 of 4770")
	)
	(layers
		(0 "F.Cu" signal "TOP")
		(4 "In1.Cu" signal "L2GND")
		(6 "In2.Cu" signal "L3")
		(8 "In3.Cu" signal "L4GND")
		(10 "In4.Cu" signal "L5")
		(12 "In5.Cu" signal "L6GND")
		(14 "In6.Cu" signal "L7VCC")
		(16 "In7.Cu" signal "L8VCC")
		(18 "In8.Cu" signal "L9GND")
		(20 "In9.Cu" signal "L10")
		(22 "In10.Cu" signal "L11GND")
		(24 "In11.Cu" signal "L12")
		(26 "In12.Cu" signal "L13GND")
		(2 "B.Cu" signal "BOTTOM")
		(9 "F.Adhes" user "F.Adhesive")
		(11 "B.Adhes" user "B.Adhesive")
		(13 "F.Paste" user "Package Geometry/Pastemask Top")
		(15 "B.Paste" user "Package Geometry/Pastemask Bottom")
		(5 "F.SilkS" user "Ref Des/Silkscreen Top")
		(7 "B.SilkS" user "Ref Des/Silkscreen Bottom")
		(1 "F.Mask" user "Board Geometry/Soldermask Top")
		(3 "B.Mask" user "Board Geometry/Soldermask Bottom")
		(17 "Dwgs.User" user "User.Drawings")
		(19 "Cmts.User" user "User.Comments")
		(21 "Eco1.User" user "User.Eco1")
		(23 "Eco2.User" user "User.Eco2")
		(25 "Edge.Cuts" user "Board Geometry/Outline")
		(27 "Margin" user)
		(31 "F.CrtYd" user "Package Geometry/Place Bound Top")
		(29 "B.CrtYd" user "Package Geometry/Place Bound Bottom")
		(35 "F.Fab" user "Ref Des/Assembly Top")
		(33 "B.Fab" user "Ref Des/Assembly Bottom")
	)
	(footprint ""
		(layer "B.Cu")
		(at 490.203998 -35.445192 180)
		(property "Reference" "U9F1"
			(at -3.03276 3.60553 180)
			(unlocked yes)
			(layer "B.SilkS")
			(effects
				(font
					(size 0.7874 0.5842)
					(thickness 0.1524)
				)
				(justify mirror)
			)
		)
		(property "Value" ""
			(at 0 0 0)
			(layer "B.Fab")
			(effects
				(font
					(size 1.27 1.27)
				)
				(justify mirror)
			)
		)
		(duplicate_pad_numbers_are_jumpers no)
		(fp_line
			(start -1.269238 1.8034)
			(end -1.77673 1.8034)
			(stroke
				(width 0.1524)
				(type default)
			)
			(layer "B.SilkS")
		)
		(fp_line
			(start -1.269238 -0.3048)
			(end -1.77673 -0.3048)
			(stroke
				(width 0.1524)
				(type default)
			)
			(layer "B.SilkS")
		)
		(fp_circle
			(center -0.149606 -0.7366)
			(end -0.276606 -0.7366)
			(stroke
				(width 0.635)
				(type default)
			)
			(fill no)
			(layer "B.SilkS")
		)
		(fp_rect
			(start -0.3302 1.8034)
			(end -2.7432 -0.3048)
			(stroke
				(width 0)
				(type default)
			)
			(fill no)
			(layer "B.CrtYd")
		)
		(fp_line
			(start -0.3302 1.8034)
			(end -0.3302 -0.3048)
			(stroke
				(width 0.1)
				(type default)
			)
			(layer "B.Fab")
		)
		(fp_line
			(start -0.3302 -0.3048)
			(end -2.7432 -0.3048)
			(stroke
				(width 0.1)
				(type default)
			)
			(layer "B.Fab")
		)
		(fp_line
			(start -2.7432 1.8034)
			(end -0.3302 1.8034)
			(stroke
				(width 0.1)
				(type default)
			)
			(layer "B.Fab")
		)
		(fp_line
			(start -2.7432 -0.3048)
			(end -2.7432 1.8034)
			(stroke
				(width 0.1)
				(type default)
			)
			(layer "B.Fab")
		)
		(fp_circle
			(center -0.149606 -0.7366)
			(end -0.276606 -0.7366)
			(stroke
				(width 0.254)
				(type default)
			)
			(fill no)
			(layer "B.Fab")
		)
		(pad "1" smd rect
			(at 0 0)
			(size 1.524 0.254)
			(layers "B.Cu" "B.Mask" "B.Paste")
			(net "SP2_BMC_CM_UART_RX_R")
		)
		(pad "2" smd rect
			(at 0 0.499872)
			(size 1.524 0.254)
			(layers "B.Cu" "B.Mask" "B.Paste")
			(net "UART_BMC_RXD5")
		)
		(pad "3" smd rect
			(at 0 0.999744)
			(size 1.524 0.254)
			(layers "B.Cu" "B.Mask" "B.Paste")
			(net "SP1_BMC_HOST_UART_RX")
		)
		(pad "4" smd rect
			(at 0 1.499616)
			(size 1.524 0.254)
			(layers "B.Cu" "B.Mask" "B.Paste")
			(net "GND")
		)
		(pad "5" smd rect
			(at -3.048 1.499616)
			(size 1.524 0.254)
			(layers "B.Cu" "B.Mask" "B.Paste")
			(net "FM_UARTSW_MSB_N")
		)
		(pad "6" smd rect
			(at -3.048 0.999744)
			(size 1.524 0.254)
			(layers "B.Cu" "B.Mask" "B.Paste")
			(net "FM_UARTSW_LSB_N")
		)
		(pad "7" smd rect
			(at -3.048 0.499872)
			(size 1.524 0.254)
			(layers "B.Cu" "B.Mask" "B.Paste")
			(net "UART_MUX_IN_R")
		)
		(pad "8" smd rect
			(at -3.048 0)
			(size 1.524 0.254)
			(layers "B.Cu" "B.Mask" "B.Paste")
			(net "P3V3_STBY")
		)
	)
	(footprint ""
		(layer "B.Cu")
		(at 422.3004 -13.335)
		(property "Reference" "R2T5"
			(at 0 0 0)
			(layer "B.SilkS")
			(hide yes)
			(effects
				(font
					(size 1.27 1.27)
				)
				(justify mirror)
			)
		)
		(property "Value" ""
			(at 0 0 0)
			(layer "B.Fab")
			(effects
				(font
					(size 1.27 1.27)
				)
				(justify mirror)
			)
		)
		(duplicate_pad_numbers_are_jumpers no)
		(fp_poly
			(pts
				(xy 0.2794 -0.1016) (xy -0.2794 -0.1016) (xy -0.2794 0.9906) (xy 0.2794 0.9906)
			)
			(stroke
				(width 0)
				(type default)
			)
			(fill no)
			(layer "B.CrtYd")
		)
		(fp_line
			(start -0.2794 -0.1016)
			(end 0.2794 -0.1016)
			(stroke
				(width 0.1)
				(type default)
			)
			(layer "B.Fab")
		)
		(fp_line
			(start -0.2794 0.9906)
			(end -0.2794 -0.1016)
			(stroke
				(width 0.1)
				(type default)
			)
			(layer "B.Fab")
		)
		(fp_line
			(start 0.2794 -0.1016)
			(end 0.2794 0.9906)
			(stroke
				(width 0.1)
				(type default)
			)
			(layer "B.Fab")
		)
		(fp_line
			(start 0.2794 0.9906)
			(end -0.2794 0.9906)
			(stroke
				(width 0.1)
				(type default)
			)
			(layer "B.Fab")
		)
		(pad "1" smd rect
			(at 0 0 180)
			(size 0.508 0.508)
			(layers "B.Cu" "B.Mask" "B.Paste")
			(net "P3V3_STBY")
		)
		(pad "2" smd rect
			(at 0 0.889 180)
			(size 0.508 0.508)
			(layers "B.Cu" "B.Mask" "B.Paste")
			(net "H_CPU0_FAST_WAKE")
		)
		(zone
			(layer "B.Cu")
			(hatch none 0.5)
			(connect_pads
				(clearance 0)
			)
			(min_thickness 0.25)
			(keepout
				(tracks allowed)
				(vias not_allowed)
				(pads allowed)
				(copperpour not_allowed)
				(footprints allowed)
			)
			(placement
				(enabled no)
				(sheetname "")
			)
			(fill
				(thermal_gap 0.5)
				(thermal_bridge_width 0.5)
				(island_removal_mode 0)
			)
			(polygon
				(pts
					(xy 422.5544 -13.081) (xy 422.0464 -13.081) (xy 422.0464 -12.7) (xy 422.5544 -12.7)
				)
			)
		)
		(zone
			(layer "B.Cu")
			(hatch none 0.5)
			(connect_pads
				(clearance 0)
			)
			(min_thickness 0.25)
			(keepout
				(tracks not_allowed)
				(vias allowed)
				(pads allowed)
				(copperpour not_allowed)
				(footprints allowed)
			)
			(placement
				(enabled no)
				(sheetname "")
			)
			(fill
				(thermal_gap 0.5)
				(thermal_bridge_width 0.5)
				(island_removal_mode 0)
			)
			(polygon
				(pts
					(xy 422.5544 -12.7) (xy 422.0464 -12.7) (xy 422.0464 -13.081) (xy 422.5544 -13.081)
				)
			)
		)
	)
	(footprint ""
		(layer "B.Cu")
		(at 411.5435 -33.401 -90)
		(property "Reference" "C25W48"
			(at 0.8382 -0.67818 270)
			(unlocked yes)
			(layer "B.SilkS")
			(effects
				(font
					(size 0.4064 0.254)
					(thickness 0.1524)
				)
				(justify left mirror)
			)
		)
		(property "Value" ""
			(at 0 0 90)
			(layer "B.Fab")
			(effects
				(font
					(size 1.27 1.27)
				)
				(justify mirror)
			)
		)
		(duplicate_pad_numbers_are_jumpers no)
		(fp_poly
			(pts
				(xy -0.3048 -0.1016) (xy -0.3048 0.9906) (xy 0.3048 0.9906) (xy 0.3048 -0.1016)
			)
			(stroke
				(width 0)
				(type default)
			)
			(fill no)
			(layer "B.CrtYd")
		)
		(fp_line
			(start -0.3048 0.9906)
			(end -0.3048 -0.1016)
			(stroke
				(width 0.1)
				(type default)
			)
			(layer "B.Fab")
		)
		(fp_line
			(start 0.3048 0.9906)
			(end -0.3048 0.9906)
			(stroke
				(width 0.1)
				(type default)
			)
			(layer "B.Fab")
		)
		(fp_line
			(start -0.3048 -0.1016)
			(end 0.3048 -0.1016)
			(stroke
				(width 0.1)
				(type default)
			)
			(layer "B.Fab")
		)
		(fp_line
			(start 0.3048 -0.1016)
			(end 0.3048 0.9906)
			(stroke
				(width 0.1)
				(type default)
			)
			(layer "B.Fab")
		)
		(pad "1" smd rect
			(at 0 0 90)
			(size 0.508 0.508)
			(layers "B.Cu" "B.Mask" "B.Paste")
			(net "P3V3_STBY")
		)
		(pad "2" smd rect
			(at 0 0.889 90)
			(size 0.508 0.508)
			(layers "B.Cu" "B.Mask" "B.Paste")
			(net "GND")
		)
		(zone
			(layer "B.Cu")
			(hatch none 0.5)
			(connect_pads
				(clearance 0)
			)
			(min_thickness 0.25)
			(keepout
				(tracks not_allowed)
				(vias allowed)
				(pads allowed)
				(copperpour not_allowed)
				(footprints allowed)
			)
			(placement
				(enabled no)
				(sheetname "")
			)
			(fill
				(thermal_gap 0.5)
				(thermal_bridge_width 0.5)
				(island_removal_mode 0)
			)
			(polygon
				(pts
					(xy 410.9085 -33.147) (xy 410.9085 -33.655) (xy 411.2895 -33.655) (xy 411.2895 -33.147)
				)
			)
		)
		(zone
			(layer "B.Cu")
			(hatch none 0.5)
			(connect_pads
				(clearance 0)
			)
			(min_thickness 0.25)
			(keepout
				(tracks allowed)
				(vias not_allowed)
				(pads allowed)
				(copperpour not_allowed)
				(footprints allowed)
			)
			(placement
				(enabled no)
				(sheetname "")
			)
			(fill
				(thermal_gap 0.5)
				(thermal_bridge_width 0.5)
				(island_removal_mode 0)
			)
			(polygon
				(pts
					(xy 411.2895 -33.147) (xy 411.2895 -33.655) (xy 410.9085 -33.655) (xy 410.9085 -33.147)
				)
			)
		)
	)
)
